# S9S_MB_2U (Grand Teton) — schematic netlist excerpt (pin names and nets, part order shuffled) for the footprints in the layout excerpt that follows; sources: Cadence DE-HDL packaged netlist, KiCad conversion of 03242023_DA0F0TMBIJ0_F0T_Motherboard_J_brd_V01_OCP.brd

R4102  Q_RES  10K 1% CHIP  pkg 0402LF  page 183 : A = PD_PCH_GPPC_C5 ; B = GND
PC1654  Q_CAP  100NF 50V 10% X7R  pkg C0402  page 272 : A = P12V_AUX ; B = GND

DB10  TDR_3P  EMPTY  pkg TH2  page 309
  GND  = T1_GND
  IO1  = TDR_SE_50_OHM_IN3
  IO2  = TDR_SE_50_OHM_IN3

(kicad_pcb
	(version 20260206)
	(generator "pcbnew")
	(generator_version "10.0")
	(general
		(thickness 1.6)
		(legacy_teardrops no)
	)
	(paper "A4")
	(title_block
		(title "03242023_DA0F0TMBIJ0_F0T_Motherboard_J_brd_V01_OCP.brd")
		(comment 1 "Grand Teton / footprints 1442-1444 of 6105")
	)
	(layers
		(0 "F.Cu" signal "TOP")
		(4 "In1.Cu" signal "GND")
		(6 "In2.Cu" signal "IN1")
		(8 "In3.Cu" signal "GND1")
		(10 "In4.Cu" signal "IN2")
		(12 "In5.Cu" signal "GND2")
		(14 "In6.Cu" signal "IN3")
		(16 "In7.Cu" signal "GND3")
		(18 "In8.Cu" signal "VCC")
		(20 "In9.Cu" signal "VCC1")
		(22 "In10.Cu" signal "GND4")
		(24 "In11.Cu" signal "IN4")
		(26 "In12.Cu" signal "GND5")
		(28 "In13.Cu" signal "IN5")
		(30 "In14.Cu" signal "GND6")
		(32 "In15.Cu" signal "IN6")
		(34 "In16.Cu" signal "GND7")
		(2 "B.Cu" signal "BOTTOM")
		(9 "F.Adhes" user "F.Adhesive")
		(11 "B.Adhes" user "B.Adhesive")
		(13 "F.Paste" user "Package Geometry/Pastemask Top")
		(15 "B.Paste" user "Package Geometry/Pastemask Bottom")
		(5 "F.SilkS" user "Ref Des/Silkscreen Top")
		(7 "B.SilkS" user "Ref Des/Silkscreen Bottom")
		(1 "F.Mask" user "Board Geometry/Soldermask Top")
		(3 "B.Mask" user "Board Geometry/Soldermask Bottom")
		(17 "Dwgs.User" user "User.Drawings")
		(19 "Cmts.User" user "User.Comments")
		(21 "Eco1.User" user "User.Eco1")
		(23 "Eco2.User" user "User.Eco2")
		(25 "Edge.Cuts" user "Board Geometry/Outline")
		(27 "Margin" user)
		(31 "F.CrtYd" user "Package Geometry/Place Bound Top")
		(29 "B.CrtYd" user "Package Geometry/Place Bound Bottom")
		(35 "F.Fab" user "Ref Des/Assembly Top")
		(33 "B.Fab" user "Ref Des/Assembly Bottom")
	)
	(footprint ""
		(layer "F.Cu")
		(at 309.523638 -36.806886 180)
		(property "Reference" "R4102"
			(at 0 0 180)
			(layer "F.SilkS")
			(hide yes)
			(effects
				(font
					(size 1.27 1.27)
				)
			)
		)
		(property "Value" ""
			(at 0 0 180)
			(layer "F.Fab")
			(effects
				(font
					(size 1.27 1.27)
				)
			)
		)
		(duplicate_pad_numbers_are_jumpers no)
		(fp_line
			(start 0.7874 0.4064)
			(end -0.7874 0.4064)
			(stroke
				(width 0.1524)
				(type default)
			)
			(layer "F.SilkS")
		)
		(fp_line
			(start 0.7874 -0.4064)
			(end 0.7874 0.4064)
			(stroke
				(width 0.1524)
				(type default)
			)
			(layer "F.SilkS")
		)
		(fp_line
			(start -0.7874 0.4064)
			(end -0.7874 -0.4064)
			(stroke
				(width 0.1524)
				(type default)
			)
			(layer "F.SilkS")
		)
		(fp_line
			(start -0.7874 -0.4064)
			(end 0.7874 -0.4064)
			(stroke
				(width 0.1524)
				(type default)
			)
			(layer "F.SilkS")
		)
		(fp_line
			(start 0.67945 0.3048)
			(end 0.120396 0.3048)
			(stroke
				(width 0.1)
				(type default)
			)
			(layer "F.Fab")
		)
		(fp_line
			(start 0.67945 -0.3048)
			(end 0.67945 0.3048)
			(stroke
				(width 0.1)
				(type default)
			)
			(layer "F.Fab")
		)
		(fp_line
			(start 0.12065 -0.2794)
			(end 0.12065 -0.3048)
			(stroke
				(width 0.1)
				(type default)
			)
			(layer "F.Fab")
		)
		(fp_line
			(start 0.12065 -0.3048)
			(end 0.67945 -0.3048)
			(stroke
				(width 0.1)
				(type default)
			)
			(layer "F.Fab")
		)
		(fp_line
			(start 0.120396 0.3048)
			(end 0.120396 0.2794)
			(stroke
				(width 0.1)
				(type default)
			)
			(layer "F.Fab")
		)
		(fp_line
			(start 0.120396 0.2794)
			(end -0.12065 0.2794)
			(stroke
				(width 0.1)
				(type default)
			)
			(layer "F.Fab")
		)
		(fp_line
			(start -0.12065 0.3048)
			(end -0.67945 0.3048)
			(stroke
				(width 0.1)
				(type default)
			)
			(layer "F.Fab")
		)
		(fp_line
			(start -0.12065 0.2794)
			(end -0.12065 0.3048)
			(stroke
				(width 0.1)
				(type default)
			)
			(layer "F.Fab")
		)
		(fp_line
			(start -0.12065 -0.2794)
			(end 0.12065 -0.2794)
			(stroke
				(width 0.1)
				(type default)
			)
			(layer "F.Fab")
		)
		(fp_line
			(start -0.12065 -0.305054)
			(end -0.12065 -0.2794)
			(stroke
				(width 0.1)
				(type default)
			)
			(layer "F.Fab")
		)
		(fp_line
			(start -0.67945 0.3048)
			(end -0.67945 -0.305054)
			(stroke
				(width 0.1)
				(type default)
			)
			(layer "F.Fab")
		)
		(fp_line
			(start -0.67945 -0.305054)
			(end -0.12065 -0.305054)
			(stroke
				(width 0.1)
				(type default)
			)
			(layer "F.Fab")
		)
		(pad "1" smd circle
			(at -0.40005 0 180)
			(size 0 0)
			(layers "F.Cu" "F.Mask" "F.Paste")
			(net "PD_PCH_GPPC_C5")
		)
		(pad "2" smd circle
			(at 0.40005 0 180)
			(size 0 0)
			(layers "F.Cu" "F.Mask" "F.Paste")
			(net "GND")
		)
	)
	(footprint ""
		(layer "F.Cu")
		(at 483.262432 -251.033788)
		(property "Reference" "DB10"
			(at 2.310384 2.86004 90)
			(unlocked yes)
			(layer "F.SilkS")
			(effects
				(font
					(size 0.7874 0.5842)
					(thickness 0.1524)
				)
				(justify left)
			)
		)
		(property "Value" ""
			(at 0 0 0)
			(layer "F.Fab")
			(effects
				(font
					(size 1.27 1.27)
				)
			)
		)
		(duplicate_pad_numbers_are_jumpers no)
		(fp_line
			(start -3.330702 -4.771136)
			(end 3.330702 -4.771136)
			(stroke
				(width 0.1524)
				(type default)
			)
			(layer "F.SilkS")
		)
		(fp_line
			(start 0 4.011168)
			(end -3.330702 -4.771136)
			(stroke
				(width 0.1524)
				(type default)
			)
			(layer "F.SilkS")
		)
		(fp_line
			(start 3.330702 -4.771136)
			(end 0 4.011168)
			(stroke
				(width 0.1524)
				(type default)
			)
			(layer "F.SilkS")
		)
		(fp_line
			(start -3.330702 -4.771136)
			(end 3.330702 -4.771136)
			(stroke
				(width 0.1)
				(type default)
			)
			(layer "F.Fab")
		)
		(fp_line
			(start 0 4.011168)
			(end -3.330702 -4.771136)
			(stroke
				(width 0.1)
				(type default)
			)
			(layer "F.Fab")
		)
		(fp_line
			(start 3.330702 -4.771136)
			(end 0 4.011168)
			(stroke
				(width 0.1)
				(type default)
			)
			(layer "F.Fab")
		)
		(pad "1" thru_hole circle
			(at 0 0)
			(size 2.159 2.159)
			(drill 1.7018)
			(layers "*.Cu" "*.Mask")
			(remove_unused_layers no)
			(net "T1_GND")
			(clearance 0.0254)
			(thermal_gap 0.0254)
		)
		(pad "2" thru_hole circle
			(at -1.27 -3.348736)
			(size 2.159 2.159)
			(drill 1.7018)
			(layers "*.Cu" "*.Mask")
			(remove_unused_layers no)
			(net "TDR_SE_50_OHM_IN3")
			(clearance 0.0254)
			(thermal_gap 0.0254)
		)
		(pad "3" thru_hole circle
			(at 1.27 -3.348736)
			(size 2.159 2.159)
			(drill 1.7018)
			(layers "*.Cu" "*.Mask")
			(remove_unused_layers no)
			(net "TDR_SE_50_OHM_IN3")
			(clearance 0.0254)
			(thermal_gap 0.0254)
		)
	)
	(footprint ""
		(layer "F.Cu")
		(at 417.730178 -375.08053)
		(property "Reference" "PC1654"
			(at 0 0 0)
			(layer "F.SilkS")
			(hide yes)
			(effects
				(font
					(size 1.27 1.27)
				)
			)
		)
		(property "Value" ""
			(at 0 0 0)
			(layer "F.Fab")
			(effects
				(font
					(size 1.27 1.27)
				)
			)
		)
		(duplicate_pad_numbers_are_jumpers no)
		(fp_line
			(start -0.7874 -0.4064)
			(end 0.7874 -0.4064)
			(stroke
				(width 0.1524)
				(type default)
			)
			(layer "F.SilkS")
		)
		(fp_line
			(start -0.7874 0.4064)
			(end -0.7874 -0.4064)
			(stroke
				(width 0.1524)
				(type default)
			)
			(layer "F.SilkS")
		)
		(fp_line
			(start 0.7874 -0.4064)
			(end 0.7874 0.4064)
			(stroke
				(width 0.1524)
				(type default)
			)
			(layer "F.SilkS")
		)
		(fp_line
			(start 0.7874 0.4064)
			(end -0.7874 0.4064)
			(stroke
				(width 0.1524)
				(type default)
			)
			(layer "F.SilkS")
		)
		(fp_line
			(start -0.67945 -0.305054)
			(end -0.12065 -0.305054)
			(stroke
				(width 0.1)
				(type default)
			)
			(layer "F.Fab")
		)
		(fp_line
			(start -0.67945 0.3048)
			(end -0.67945 -0.305054)
			(stroke
				(width 0.1)
				(type default)
			)
			(layer "F.Fab")
		)
		(fp_line
			(start -0.12065 -0.305054)
			(end -0.12065 -0.2794)
			(stroke
				(width 0.1)
				(type default)
			)
			(layer "F.Fab")
		)
		(fp_line
			(start -0.12065 -0.2794)
			(end 0.12065 -0.2794)
			(stroke
				(width 0.1)
				(type default)
			)
			(layer "F.Fab")
		)
		(fp_line
			(start -0.12065 0.2794)
			(end -0.12065 0.3048)
			(stroke
				(width 0.1)
				(type default)
			)
			(layer "F.Fab")
		)
		(fp_line
			(start -0.12065 0.3048)
			(end -0.67945 0.3048)
			(stroke
				(width 0.1)
				(type default)
			)
			(layer "F.Fab")
		)
		(fp_line
			(start 0.120396 0.2794)
			(end -0.12065 0.2794)
			(stroke
				(width 0.1)
				(type default)
			)
			(layer "F.Fab")
		)
		(fp_line
			(start 0.120396 0.3048)
			(end 0.120396 0.2794)
			(stroke
				(width 0.1)
				(type default)
			)
			(layer "F.Fab")
		)
		(fp_line
			(start 0.12065 -0.3048)
			(end 0.67945 -0.3048)
			(stroke
				(width 0.1)
				(type default)
			)
			(layer "F.Fab")
		)
		(fp_line
			(start 0.12065 -0.2794)
			(end 0.12065 -0.3048)
			(stroke
				(width 0.1)
				(type default)
			)
			(layer "F.Fab")
		)
		(fp_line
			(start 0.67945 -0.3048)
			(end 0.67945 0.3048)
			(stroke
				(width 0.1)
				(type default)
			)
			(layer "F.Fab")
		)
		(fp_line
			(start 0.67945 0.3048)
			(end 0.120396 0.3048)
			(stroke
				(width 0.1)
				(type default)
			)
			(layer "F.Fab")
		)
		(pad "1" smd circle
			(at -0.40005 0)
			(size 0 0)
			(layers "F.Cu" "F.Mask" "F.Paste")
			(net "P12V_AUX")
		)
		(pad "2" smd circle
			(at 0.40005 0)
			(size 0 0)
			(layers "F.Cu" "F.Mask" "F.Paste")
			(net "GND")
		)
	)
)
